1-Board Name: Timing card
2-Stackup
Doc Number: R4006-B0001 1-VendorName
3-Date: 9/15/2021 2-Date
4-Doc Rev: 1.1 3-UL 
5-Designer <name>
<email> 4-Panel Size
6-Reviewer <name>
5-UR
7-Total Layers: 10 6-Designer 
8-Board Thickness: 1.57mm +/- 0.13 7-Vendor 
9-PCB Material: TU863+ VLP
10-Minimum Pitch 1.0mm BGA
11-Minimum Finished 
Via Size
12-Estimated Via 
Number
13-Special via  For via of finish hole size xxx mil, drill size should be yyy mil.
14-Minimum Trace 
Width/Spacing
15-Pannel Size Refer to panel drawing
16-Pannel Rotation Please proposal can ratate or not
17-Surface Finish: OSP
18-Hole plugging Refer to Fab notes if no other 
specified requirements
19-Hole Plating 
Thickness 1.0 mil Average
20-Special
Requirements 1  Gold finger
21-PCB outline: Refer to Gerber
22-Backdrilling Yes, Tolerance: 7+/-5 mil
23-Backdrill hole D+xx mil (for via drill hole yymil)
24-BD2M xxmil
25-D2M xxmil
26- UL qualified on All 
Copper/Core/PP NA
27-Quotation or Price
Stackup Control Table
---
Layer Type Thickness 
(mil)
2-Ply 
Required Fibre Type/Copper Weight (oz) copper foil
 type
等效DK(For impedance 
calculating)
Impedance spec (Ohms) Reference layer Width 
(/space):mil Sim Z0
SM SM
S54±10% 2 4 53.5
S50±10% 2 4.7 49.9
D85±10% 2 5.7/9.3 85.2
D88±10% 2 3.9/4.1 88.0
D100±10% 2 3.9/8.1 100.0
D85 Neckdown, 85±10% 2 3.6/3.5 86.8
D100Neckdown, 100±10% 2 3.0/4.5 98.3
Prepreg 2.80 N 1080x1 RC63%
2 GND1 0.62 0.5 oz(VLP) VLP
Core 5.00 Y 1078x2
S50±10% 2&4 5 49.93
D85±10% 2&4 6.2/6.8 84.85
D95±10% 2&4 4.0/4.0 95.35
D100±10% 2&4 4.6/7.9 99.83
D85 Neckdown, 85±10% 2&4 4.5/3.0 85.34
D100Neckdown, 100±10% 2&4 3.5/4.0 100.4
Prepreg 5.04 N 2116x1 RC58%
4 GND2 1.20 1 oz(VLP) VLP
Core 5.00 N 2116x1
5 VCC1 1.20 1 oz(VLP) VLP
Prepreg 14.92 Y 7628x2 RC43%
6 VCC2 1.20 1 oz(VLP) VLP
Core 5.00 N 2116x1
7 GND3 1.20 1 oz(VLP) VLP
Prepreg 5.04 N 2116x1 RC58%
S50±10% 7&9 5 49.93
D85±10% 7&9 6.2/6.8 84.85
D95±10% 7&9 4.0/4.0 95.35
D100±10% 7&9 4.6/7.9 99.83
D85 Neckdown, 85±10% 7&9 4.5/3.0 85.34
D100Neckdown, 100±10% 7&9 3.5/4.0 100.4
Core 5.00 Y 1078x2
9 GND4 0.62 0.5 oz(VLP) VLP
Prepreg 2.80 N 1080x1 RC63%
S54±10% 9 4 53.5
S50±10% 9 4.7 49.9
D85±10% 9 5.7/9.3 85.2
D88±10% 9 3.9/4.1 88.0
D100±10% 9 3.9/8.1 100.0
D85 Neckdown, 85±10% 9 3.6/3.5 86.8
D100Neckdown, 100±10% 9 3.0/4.5 98.3
SM SM
61.94 mil Gold finger,without solder mask
1.57 mm
Revision Description Date
1.0 First release 2021/9/18
1.1 Modify some typos. Delete inner layer 
47ohm requirement. 2021/9/22
Board Thickness:
Sheet Revision
10 BOTTOM 2.05 0.5 oz + plating(HTE) HTE 3.29
Sig2 0.60 VLP
3.29
Sig1 0.60 VLP
1 TOP 2.05 0.5 oz + 
plating(HTE) HTE
Structure Vendor proposed Vendor Proposed
Board Information
Vendor Information Notes from Celestica:
1. For "Neckdown" traces, if the trace width/space you calculate is larger than 4 mil/4 mil, please do not control the 
impedance but need vendor to calculate the impedance with the fixed trace width/space;if the trace width/space you 
calculate is less than 4 mil/4 mil, please use the trace width/spacing to control the impedance.  
2.Please do not use 1500 series for prepreg and core between signal layer and GND layer.
3.As no Gerber, signal layer copper 30% and GND/VCC layer copper 70% assumed.
4.Please keep no more than one decimal for trace width and spacing.
5.Do not use 7628 and 1500 series for signal layers.
6.Do not use 106 and 1080 prepreg and core for signal layers, but can be used for VCC layers.
7.Copper finish is VLP
8.Impedance tolerance is  ±10%
9.Board thickness tolerance is  ±10%.
10. Neckdown trace should also have impedance control. The neckdown trace impedance tolerance is ±10%.